(kicad_pcb
	(version 20260206)
	(generator "pcbnew")
	(generator_version "10.0")
	(general
		(thickness 1.6)
		(legacy_teardrops no)
	)
	(paper "A4")
	(title_block
		(title "04192023_DAF0TMB3IC0_F0TG_MB_C_brd_V02_OCP.brd")
		(comment 1 "Grand Teton / footprint 3169 of 8354 (U6016), pads 337-354 of 354")
	)
	(layers
		(0 "F.Cu" signal "TOP")
		(4 "In1.Cu" signal "GND")
		(6 "In2.Cu" signal "IN1")
		(8 "In3.Cu" signal "GND1")
		(10 "In4.Cu" signal "IN2")
		(12 "In5.Cu" signal "GND2")
		(14 "In6.Cu" signal "IN3")
		(16 "In7.Cu" signal "GND3")
		(18 "In8.Cu" signal "VCC")
		(20 "In9.Cu" signal "VCC1")
		(22 "In10.Cu" signal "GND4")
		(24 "In11.Cu" signal "IN4")
		(26 "In12.Cu" signal "GND5")
		(28 "In13.Cu" signal "IN5")
		(30 "In14.Cu" signal "GND6")
		(32 "In15.Cu" signal "IN6")
		(34 "In16.Cu" signal "GND7")
		(2 "B.Cu" signal "BOTTOM")
		(9 "F.Adhes" user "F.Adhesive")
		(11 "B.Adhes" user "B.Adhesive")
		(13 "F.Paste" user "Package Geometry/Pastemask Top")
		(15 "B.Paste" user "Package Geometry/Pastemask Bottom")
		(5 "F.SilkS" user "Ref Des/Silkscreen Top")
		(7 "B.SilkS" user "Ref Des/Silkscreen Bottom")
		(1 "F.Mask" user "Board Geometry/Soldermask Top")
		(3 "B.Mask" user "Board Geometry/Soldermask Bottom")
		(17 "Dwgs.User" user "User.Drawings")
		(19 "Cmts.User" user "User.Comments")
		(21 "Eco1.User" user "User.Eco1")
		(23 "Eco2.User" user "User.Eco2")
		(25 "Edge.Cuts" user "Board Geometry/Outline")
		(27 "Margin" user)
		(31 "F.CrtYd" user "Package Geometry/Place Bound Top")
		(29 "B.CrtYd" user "Package Geometry/Place Bound Bottom")
		(35 "F.Fab" user "Ref Des/Assembly Top")
		(33 "B.Fab" user "Ref Des/Assembly Bottom")
	)
	(footprint ""
		(layer "F.Cu")
		(at 156.0957 -387.342634)
		(property "Reference" "U6016"
			(at -8.08609 -8.07466 0)
			(unlocked yes)
			(layer "F.SilkS")
			(effects
				(font
					(size 0.7874 0.5842)
					(thickness 0.1524)
				)
				(justify left)
			)
		)
		(property "Value" ""
			(at 0 0 0)
			(layer "F.Fab")
			(effects
				(font
					(size 1.27 1.27)
				)
			)
		)
		(duplicate_pad_numbers_are_jumpers no)
		(pad "P10" smd circle
			(at 8.802624 -1.431798)
			(size 0.381 0.381)
			(layers "F.Cu" "F.Mask" "F.Paste")
			(net "P5E_CPU1_P2_TX_BUF_DN<15>")
		)
		(pad "P29" smd circle
			(at 8.802624 2.032254)
			(size 0.381 0.381)
			(layers "F.Cu" "F.Mask" "F.Paste")
			(net "P5E_CPU1_P2_RX_DN<15>")
		)
		(pad "R1" smd oval
			(at 8.64997 -3.938524)
			(size 0.254 0.3302)
			(layers "F.Cu" "F.Mask" "F.Paste")
			(net "P5E_CPU1_P2_RX_BUF_DP<15>")
		)
		(pad "R35" smd oval
			(at 8.64997 3.940048)
			(size 0.254 0.3302)
			(layers "F.Cu" "F.Mask" "F.Paste")
			(net "P5E_CPU1_P2_TX_C_DP<15>")
		)
		(pad "T4" smd circle
			(at 8.402574 -2.817368)
			(size 0.381 0.381)
			(layers "F.Cu" "F.Mask" "F.Paste")
			(net "GND")
		)
		(pad "T13" smd circle
			(at 8.402574 -0.79629)
			(size 0.3048 0.3048)
			(layers "F.Cu" "F.Mask" "F.Paste")
			(net "GND")
		)
		(pad "T17" smd circle
			(at 8.402574 -0.296164)
			(size 0.3048 0.3048)
			(layers "F.Cu" "F.Mask" "F.Paste")
			(net "P0V9_CPU1_RT2_2A")
		)
		(pad "T20" smd circle
			(at 8.402574 0.203708)
			(size 0.3048 0.3048)
			(layers "F.Cu" "F.Mask" "F.Paste")
			(net "P0V9_CPU1_RT2_2A")
		)
		(pad "T22" smd circle
			(at 8.402574 0.703834)
			(size 0.3048 0.3048)
			(layers "F.Cu" "F.Mask" "F.Paste")
			(net "GND")
		)
		(pad "T32" smd circle
			(at 8.402574 2.724912)
			(size 0.381 0.381)
			(layers "F.Cu" "F.Mask" "F.Paste")
			(net "GND")
		)
		(pad "U2" smd circle
			(at 8.349996 -3.41884)
			(size 0.3048 0.3048)
			(layers "F.Cu" "F.Mask" "F.Paste")
			(net "GND")
		)
		(pad "U34" smd circle
			(at 8.349996 3.420364)
			(size 0.3048 0.3048)
			(layers "F.Cu" "F.Mask" "F.Paste")
			(net "GND")
		)
		(pad "V1" smd oval
			(at 8.050022 -3.938524)
			(size 0.254 0.3302)
			(layers "F.Cu" "F.Mask" "F.Paste")
			(net "GND")
		)
		(pad "V35" smd oval
			(at 8.050022 3.940048)
			(size 0.254 0.3302)
			(layers "F.Cu" "F.Mask" "F.Paste")
			(net "GND")
		)
		(pad "W7" smd circle
			(at 8.002524 -2.12471)
			(size 0.381 0.381)
			(layers "F.Cu" "F.Mask" "F.Paste")
			(net "P5E_CPU1_P2_TX_BUF_DP<14>")
		)
		(pad "W26" smd circle
			(at 8.002524 1.339342)
			(size 0.381 0.381)
			(layers "F.Cu" "F.Mask" "F.Paste")
			(net "P5E_CPU1_P2_RX_DP<14>")
		)
		(pad "Y2" smd circle
			(at 7.750048 -3.41884)
			(size 0.3048 0.3048)
			(layers "F.Cu" "F.Mask" "F.Paste")
			(net "P5E_CPU1_P2_RX_BUF_DN<14>")
		)
		(pad "Y34" smd circle
			(at 7.750048 3.420364)
			(size 0.3048 0.3048)
			(layers "F.Cu" "F.Mask" "F.Paste")
			(net "P5E_CPU1_P2_TX_C_DN<14>")
		)
	)
)
